(kicad_pcb
	(version 20260206)
	(generator "pcbnew")
	(generator_version "10.0")
	(general
		(thickness 1.6)
		(legacy_teardrops no)
	)
	(paper "A4")
	(title_block
		(title "dpb — 14545-sa.0730WZS0815.brd")
		(comment 1 "Honey Badger (Wiwynn) / footprints 848-850 of 1066")
	)
	(layers
		(0 "F.Cu" signal "TOP")
		(4 "In1.Cu" signal "L2GND")
		(6 "In2.Cu" signal "L3")
		(8 "In3.Cu" signal "L4VCC")
		(10 "In4.Cu" signal "L5VCC")
		(12 "In5.Cu" signal "L6")
		(14 "In6.Cu" signal "L7GND")
		(2 "B.Cu" signal "BOTTOM")
		(9 "F.Adhes" user "F.Adhesive")
		(11 "B.Adhes" user "B.Adhesive")
		(13 "F.Paste" user "Package Geometry/Pastemask Top")
		(15 "B.Paste" user "Package Geometry/Pastemask Bottom")
		(5 "F.SilkS" user "Ref Des/Silkscreen Top")
		(7 "B.SilkS" user "Ref Des/Silkscreen Bottom")
		(1 "F.Mask" user "Board Geometry/Soldermask Top")
		(3 "B.Mask" user "Board Geometry/Soldermask Bottom")
		(17 "Dwgs.User" user "User.Drawings")
		(19 "Cmts.User" user "User.Comments")
		(21 "Eco1.User" user "User.Eco1")
		(23 "Eco2.User" user "User.Eco2")
		(25 "Edge.Cuts" user "Board Geometry/Outline")
		(27 "Margin" user)
		(31 "F.CrtYd" user "Package Geometry/Place Bound Top")
		(29 "B.CrtYd" user "Package Geometry/Place Bound Bottom")
		(35 "F.Fab" user "Ref Des/Assembly Top")
		(33 "B.Fab" user "Ref Des/Assembly Bottom")
	)
	(footprint ""
		(layer "F.Cu")
		(at 227.499926 -170.669966 90)
		(property "Reference" "SKT4"
			(at 0 0 90)
			(layer "F.SilkS")
			(hide yes)
			(effects
				(font
					(size 1.27 1.27)
				)
			)
		)
		(property "Value" "SKT-SATA14P-15P-12-GP"
			(at -22.6187 8.1788 90)
			(unlocked yes)
			(layer "F.Fab")
			(hide yes)
			(effects
				(font
					(size 1.016 1.016)
					(thickness 0.1524)
				)
			)
		)
		(property "Device Type" "87945-1001"
			(at -22.6187 6.6548 90)
			(unlocked yes)
			(layer "F.Fab")
			(hide yes)
			(effects
				(font
					(size 1.016 1.016)
					(thickness 0.1524)
				)
			)
		)
		(duplicate_pad_numbers_are_jumpers no)
		(fp_line
			(start -15.3924 -5.8547)
			(end -16.3576 -5.8547)
			(stroke
				(width 0.3302)
				(type default)
			)
			(layer "F.SilkS")
		)
		(fp_line
			(start 20.4724 -5.7658)
			(end 20.4724 -2.3114)
			(stroke
				(width 0.1524)
				(type default)
			)
			(layer "F.SilkS")
		)
		(fp_line
			(start -20.4724 -5.7658)
			(end 20.4724 -5.7658)
			(stroke
				(width 0.1524)
				(type default)
			)
			(layer "F.SilkS")
		)
		(fp_line
			(start 23.7617 -2.3114)
			(end 23.7617 2.3114)
			(stroke
				(width 0.1524)
				(type default)
			)
			(layer "F.SilkS")
		)
		(fp_line
			(start 20.4724 -2.3114)
			(end 23.7617 -2.3114)
			(stroke
				(width 0.1524)
				(type default)
			)
			(layer "F.SilkS")
		)
		(fp_line
			(start -20.4724 -2.3114)
			(end -20.4724 -5.7658)
			(stroke
				(width 0.1524)
				(type default)
			)
			(layer "F.SilkS")
		)
		(fp_line
			(start -23.7617 -2.3114)
			(end -20.4724 -2.3114)
			(stroke
				(width 0.1524)
				(type default)
			)
			(layer "F.SilkS")
		)
		(fp_line
			(start 23.117556 -0.5461)
			(end 23.117556 0.5461)
			(stroke
				(width 0.3048)
				(type default)
			)
			(layer "F.SilkS")
		)
		(fp_line
			(start -20.882356 -0.5461)
			(end -20.882356 0.5461)
			(stroke
				(width 0.3048)
				(type default)
			)
			(layer "F.SilkS")
		)
		(fp_line
			(start 20.882356 0.5461)
			(end 20.882356 -0.5461)
			(stroke
				(width 0.3048)
				(type default)
			)
			(layer "F.SilkS")
		)
		(fp_line
			(start -23.117556 0.5461)
			(end -23.117556 -0.5461)
			(stroke
				(width 0.3048)
				(type default)
			)
			(layer "F.SilkS")
		)
		(fp_line
			(start 23.7617 2.3114)
			(end 20.4724 2.3114)
			(stroke
				(width 0.1524)
				(type default)
			)
			(layer "F.SilkS")
		)
		(fp_line
			(start 20.4724 2.3114)
			(end 20.4724 9.652)
			(stroke
				(width 0.1524)
				(type default)
			)
			(layer "F.SilkS")
		)
		(fp_line
			(start -20.4724 2.3114)
			(end -23.7617 2.3114)
			(stroke
				(width 0.1524)
				(type default)
			)
			(layer "F.SilkS")
		)
		(fp_line
			(start -23.7617 2.3114)
			(end -23.7617 -2.3114)
			(stroke
				(width 0.1524)
				(type default)
			)
			(layer "F.SilkS")
		)
		(fp_line
			(start 17.8435 7.9502)
			(end -17.8435 7.9502)
			(stroke
				(width 0.1524)
				(type default)
			)
			(layer "F.SilkS")
		)
		(fp_line
			(start -17.8435 7.9502)
			(end -17.8435 9.652)
			(stroke
				(width 0.1524)
				(type default)
			)
			(layer "F.SilkS")
		)
		(fp_line
			(start 20.4724 9.652)
			(end 17.8435 9.652)
			(stroke
				(width 0.1524)
				(type default)
			)
			(layer "F.SilkS")
		)
		(fp_line
			(start 17.8435 9.652)
			(end 17.8435 7.9502)
			(stroke
				(width 0.1524)
				(type default)
			)
			(layer "F.SilkS")
		)
		(fp_line
			(start -17.8435 9.652)
			(end -20.4724 9.652)
			(stroke
				(width 0.1524)
				(type default)
			)
			(layer "F.SilkS")
		)
		(fp_line
			(start -20.4724 9.652)
			(end -20.4724 2.3114)
			(stroke
				(width 0.1524)
				(type default)
			)
			(layer "F.SilkS")
		)
		(fp_arc
			(start 20.882356 -0.5461)
			(mid 21.999956 -1.6637)
			(end 23.117556 -0.5461)
			(stroke
				(width 0.3048)
				(type default)
			)
			(layer "F.SilkS")
		)
		(fp_arc
			(start -23.117556 -0.5461)
			(mid -21.999956 -1.6637)
			(end -20.882356 -0.5461)
			(stroke
				(width 0.3048)
				(type default)
			)
			(layer "F.SilkS")
		)
		(fp_arc
			(start 23.117556 0.5461)
			(mid 21.999956 1.6637)
			(end 20.882356 0.5461)
			(stroke
				(width 0.3048)
				(type default)
			)
			(layer "F.SilkS")
		)
		(fp_arc
			(start -20.882356 0.5461)
			(mid -21.999956 1.6637)
			(end -23.117556 0.5461)
			(stroke
				(width 0.3048)
				(type default)
			)
			(layer "F.SilkS")
		)
		(fp_poly
			(pts
				(xy -15.87119 -5.838698) (xy -15.23619 -6.473698) (xy -16.50619 -6.473698)
			)
			(stroke
				(width 0)
				(type default)
			)
			(fill yes)
			(layer "F.SilkS")
		)
		(fp_poly
			(pts
				(xy -20.2184 -5.5118) (xy 20.2184 -5.5118) (xy 20.2184 -2.0574) (xy 23.5077 -2.0574) (xy 23.5077 2.0574)
				(xy 20.2184 2.0574) (xy 20.2184 9.398) (xy 18.0975 9.398) (xy 18.0975 7.6962) (xy -18.0975 7.6962)
				(xy -18.0975 9.398) (xy -20.2184 9.398) (xy -20.2184 2.0574) (xy -23.5077 2.0574) (xy -23.5077 -2.0574)
				(xy -20.2184 -2.0574)
			)
			(stroke
				(width 0)
				(type default)
			)
			(fill no)
			(layer "F.CrtYd")
		)
		(fp_poly
			(pts
				(xy -20.2184 -5.5118) (xy -20.2184 -6.0198) (xy -20.7264 -6.0198) (xy -20.7264 -2.5654) (xy -24.0157 -2.5654)
				(xy -24.0157 2.5654) (xy -20.7264 2.5654) (xy -20.7264 9.906) (xy -17.5895 9.906) (xy -17.5895 8.2042)
				(xy 17.5895 8.2042) (xy 17.5895 9.906) (xy 20.7264 9.906) (xy 20.7264 2.5654) (xy 24.0157 2.5654)
				(xy 24.0157 -2.5654) (xy 20.7264 -2.5654) (xy 20.7264 -6.0198) (xy -20.21586 -6.0198) (xy -20.21586 -5.5118)
				(xy 20.2184 -5.5118) (xy 20.2184 -2.0574) (xy 23.5077 -2.0574) (xy 23.5077 2.0574) (xy 20.2184 2.0574)
				(xy 20.2184 9.398) (xy 18.0975 9.398) (xy 18.0975 7.6962) (xy -18.0975 7.6962) (xy -18.0975 9.398)
				(xy -20.2184 9.398) (xy -20.2184 2.0574) (xy -23.5077 2.0574) (xy -23.5077 -2.0574) (xy -20.2184 -2.0574)
			)
			(stroke
				(width 0)
				(type default)
			)
			(fill no)
			(layer "F.CrtYd")
		)
		(fp_poly
			(pts
				(xy -20.7264 -6.0198) (xy -20.7264 -2.5654) (xy -24.0157 -2.5654) (xy -24.0157 2.5654) (xy -20.7264 2.5654)
				(xy -20.7264 9.906) (xy -17.5895 9.906) (xy -17.5895 8.2042) (xy 17.5895 8.2042) (xy 17.5895 9.906)
				(xy 20.7264 9.906) (xy 20.7264 2.5654) (xy 24.0157 2.5654) (xy 24.0157 -2.5654) (xy 20.7264 -2.5654)
				(xy 20.7264 -6.0198)
			)
			(stroke
				(width 0)
				(type default)
			)
			(fill no)
			(layer "F.Fab")
		)
		(pad "" np_thru_hole circle
			(at -18.999962 -2.350008 90)
			(size 0.254 0.254)
			(drill 1.8542)
			(layers "*.Cu" "*.Mask")
			(clearance 1.1557)
			(thermal_gap 1.1557)
		)
		(pad "" np_thru_hole circle
			(at 18.999962 -2.350008 90)
			(size 0.254 0.254)
			(drill 1.8542)
			(layers "*.Cu" "*.Mask")
			(clearance 1.1557)
			(thermal_gap 1.1557)
		)
		(pad "H1" thru_hole oval
			(at -21.999956 0 90)
			(size 1.524 2.6162)
			(drill oval 0.8128 1.905)
			(layers "*.Cu" "*.Mask")
			(remove_unused_layers no)
			(net "GND")
			(clearance 0.1524)
			(thermal_gap 0.1524)
		)
		(pad "H2" thru_hole oval
			(at 21.999956 0 90)
			(size 1.524 2.6162)
			(drill oval 0.8128 1.905)
			(layers "*.Cu" "*.Mask")
			(remove_unused_layers no)
			(net "GND")
			(clearance 0.1524)
			(thermal_gap 0.1524)
		)
		(pad "P1" smd rect
			(at -1.89992 -4.249928 90)
			(size 0.6604 2.3876)
			(layers "F.Cu" "F.Mask" "F.Paste")
			(net "Net_30")
		)
		(pad "P2" smd rect
			(at -0.62992 -4.249928 90)
			(size 0.6604 2.3876)
			(layers "F.Cu" "F.Mask" "F.Paste")
			(net "Net_29")
		)
		(pad "P3" smd rect
			(at 0.64008 -4.249928 90)
			(size 0.6604 2.3876)
			(layers "F.Cu" "F.Mask" "F.Paste")
			(net "Net_28")
		)
		(pad "P4" smd rect
			(at 1.91008 -4.249928 90)
			(size 0.6604 2.3876)
			(layers "F.Cu" "F.Mask" "F.Paste")
			(net "GND")
		)
		(pad "P5" smd rect
			(at 3.18008 -4.249928 90)
			(size 0.6604 2.3876)
			(layers "F.Cu" "F.Mask" "F.Paste")
			(net "HDD_PRSNT_NET3")
		)
		(pad "P6" smd rect
			(at 4.45008 -4.249928 90)
			(size 0.6604 2.3876)
			(layers "F.Cu" "F.Mask" "F.Paste")
			(net "GND")
		)
		(pad "P7" smd rect
			(at 5.72008 -4.249928 90)
			(size 0.6604 2.3876)
			(layers "F.Cu" "F.Mask" "F.Paste")
			(net "5V_PRE_3")
		)
		(pad "P8" smd rect
			(at 6.99008 -4.249928 90)
			(size 0.6604 2.3876)
			(layers "F.Cu" "F.Mask" "F.Paste")
			(net "P5V_HDD3")
		)
		(pad "P9" smd rect
			(at 8.26008 -4.249928 90)
			(size 0.6604 2.3876)
			(layers "F.Cu" "F.Mask" "F.Paste")
			(net "P5V_HDD3")
		)
		(pad "P10" smd rect
			(at 9.53008 -4.249928 90)
			(size 0.6604 2.3876)
			(layers "F.Cu" "F.Mask" "F.Paste")
			(net "GND")
		)
		(pad "P11" smd rect
			(at 10.80008 -4.249928 90)
			(size 0.6604 2.3876)
			(layers "F.Cu" "F.Mask" "F.Paste")
			(net "ACT_HDD3")
		)
		(pad "P12" smd rect
			(at 12.07008 -4.249928 90)
			(size 0.6604 2.3876)
			(layers "F.Cu" "F.Mask" "F.Paste")
			(net "GND")
		)
		(pad "P13" smd rect
			(at 13.34008 -4.249928 90)
			(size 0.6604 2.3876)
			(layers "F.Cu" "F.Mask" "F.Paste")
			(net "12V_PRE_3")
		)
		(pad "P14" smd rect
			(at 14.61008 -4.249928 90)
			(size 0.6604 2.3876)
			(layers "F.Cu" "F.Mask" "F.Paste")
			(net "P12V_HDD3")
		)
		(pad "P15" smd rect
			(at 15.88008 -4.249928 90)
			(size 0.6604 2.3876)
			(layers "F.Cu" "F.Mask" "F.Paste")
			(net "P12V_HDD3")
		)
		(pad "S1" smd rect
			(at -15.86992 -4.249928 90)
			(size 0.6604 2.3876)
			(layers "F.Cu" "F.Mask" "F.Paste")
			(net "GND")
		)
		(pad "S2" smd rect
			(at -14.59992 -4.249928 90)
			(size 0.6604 2.3876)
			(layers "F.Cu" "F.Mask" "F.Paste")
			(net "SAS2X28_A_HDD3_TX_+")
		)
		(pad "S3" smd rect
			(at -13.32992 -4.249928 90)
			(size 0.6604 2.3876)
			(layers "F.Cu" "F.Mask" "F.Paste")
			(net "SAS2X28_A_HDD3_TX_-")
		)
		(pad "S4" smd rect
			(at -12.05992 -4.249928 90)
			(size 0.6604 2.3876)
			(layers "F.Cu" "F.Mask" "F.Paste")
			(net "GND")
		)
		(pad "S5" smd rect
			(at -10.78992 -4.249928 90)
			(size 0.6604 2.3876)
			(layers "F.Cu" "F.Mask" "F.Paste")
			(net "SAS2X28_DRIVE_RX_N_A3")
		)
		(pad "S6" smd rect
			(at -9.51992 -4.249928 90)
			(size 0.6604 2.3876)
			(layers "F.Cu" "F.Mask" "F.Paste")
			(net "SAS2X28_DRIVE_RX_P_A3")
		)
		(pad "S7" smd rect
			(at -8.24992 -4.249928 90)
			(size 0.6604 2.3876)
			(layers "F.Cu" "F.Mask" "F.Paste")
			(net "GND")
		)
		(pad "S8" smd rect
			(at -7.480046 -2.100072 90)
			(size 0.508 1.905)
			(layers "F.Cu" "F.Mask" "F.Paste")
			(net "GND")
		)
		(pad "S9" smd rect
			(at -6.679946 -2.100072 90)
			(size 0.508 1.905)
			(layers "F.Cu" "F.Mask" "F.Paste")
			(net "SAS2X28_B_HDD3_TX_+")
		)
		(pad "S10" smd rect
			(at -5.8801 -2.100072 90)
			(size 0.508 1.905)
			(layers "F.Cu" "F.Mask" "F.Paste")
			(net "SAS2X28_B_HDD3_TX_-")
		)
		(pad "S11" smd rect
			(at -5.08 -2.100072 90)
			(size 0.508 1.905)
			(layers "F.Cu" "F.Mask" "F.Paste")
			(net "GND")
		)
		(pad "S12" smd rect
			(at -4.2799 -2.100072 90)
			(size 0.508 1.905)
			(layers "F.Cu" "F.Mask" "F.Paste")
			(net "SAS2X28_DRIVE_RX_N_B3")
		)
		(pad "S13" smd rect
			(at -3.480054 -2.100072 90)
			(size 0.508 1.905)
			(layers "F.Cu" "F.Mask" "F.Paste")
			(net "SAS2X28_DRIVE_RX_P_B3")
		)
		(pad "S14" smd rect
			(at -2.679954 -2.100072 90)
			(size 0.508 1.905)
			(layers "F.Cu" "F.Mask" "F.Paste")
			(net "GND")
		)
		(zone
			(layers "F.Cu" "B.Cu" "In1.Cu" "In2.Cu" "In3.Cu" "In4.Cu" "In5.Cu" "In6.Cu")
			(hatch none 0.5)
			(connect_pads
				(clearance 0)
			)
			(min_thickness 0.25)
			(keepout
				(tracks not_allowed)
				(vias allowed)
				(pads allowed)
				(copperpour not_allowed)
				(footprints allowed)
			)
			(placement
				(enabled no)
				(sheetname "")
			)
			(fill
				(thermal_gap 0.5)
				(thermal_bridge_width 0.5)
				(island_removal_mode 0)
			)
			(polygon
				(pts
					(arc
						(start 226.381818 -189.669928)
						(mid 223.918018 -189.669928)
						(end 226.381818 -189.669928)
					)
				)
			)
		)
		(zone
			(layers "F.Cu" "B.Cu" "In1.Cu" "In2.Cu" "In3.Cu" "In4.Cu" "In5.Cu" "In6.Cu")
			(hatch none 0.5)
			(connect_pads
				(clearance 0)
			)
			(min_thickness 0.25)
			(keepout
				(tracks not_allowed)
				(vias allowed)
				(pads allowed)
				(copperpour not_allowed)
				(footprints allowed)
			)
			(placement
				(enabled no)
				(sheetname "")
			)
			(fill
				(thermal_gap 0.5)
				(thermal_bridge_width 0.5)
				(island_removal_mode 0)
			)
			(polygon
				(pts
					(arc
						(start 226.381818 -151.670004)
						(mid 223.918018 -151.670004)
						(end 226.381818 -151.670004)
					)
				)
			)
		)
	)
	(footprint ""
		(layer "F.Cu")
		(at 26.796746 -425.732702)
		(property "Reference" "C266"
			(at 0 0 0)
			(layer "F.SilkS")
			(hide yes)
			(effects
				(font
					(size 1.27 1.27)
				)
			)
		)
		(property "Value" "SC1U16V3KX-5GP"
			(at 0 -2.8194 0)
			(unlocked yes)
			(layer "F.Fab")
			(hide yes)
			(effects
				(font
					(size 1.016 1.016)
					(thickness 0.1524)
				)
			)
		)
		(property "Device Type" "C603H36"
			(at 0 -4.3434 0)
			(unlocked yes)
			(layer "F.Fab")
			(hide yes)
			(effects
				(font
					(size 1.016 1.016)
					(thickness 0.1524)
				)
			)
		)
		(duplicate_pad_numbers_are_jumpers no)
		(fp_line
			(start 0.508 0)
			(end -0.508 0)
			(stroke
				(width 0.2032)
				(type default)
			)
			(layer "F.SilkS")
		)
		(fp_rect
			(start -0.5842 1.3335)
			(end 0.5842 -1.3335)
			(stroke
				(width 0)
				(type default)
			)
			(fill no)
			(layer "F.CrtYd")
		)
		(fp_rect
			(start -0.5842 1.3335)
			(end 0.5842 -1.3335)
			(stroke
				(width 0)
				(type default)
			)
			(fill no)
			(layer "F.Fab")
		)
		(pad "1" smd custom
			(at 0 -0.762)
			(size 0.2159 0.2159)
			(layers "F.Cu" "F.Mask" "F.Paste")
			(net "P5V_HDD10")
			(options
				(clearance outline)
				(anchor circle)
			)
			(primitives
				(gr_poly
					(pts
						(arc
							(start -0.3302 -0.4318)
							(mid -0.402042 -0.402042)
							(end -0.4318 -0.3302)
						)
						(arc
							(start -0.4318 0.3302)
							(mid -0.402042 0.402042)
							(end -0.3302 0.4318)
						)
						(arc
							(start 0.3302 0.4318)
							(mid 0.402042 0.402042)
							(end 0.4318 0.3302)
						)
						(arc
							(start 0.4318 -0.3302)
							(mid 0.402042 -0.402042)
							(end 0.3302 -0.4318)
						)
					)
					(width 0)
					(fill yes)
				)
			)
		)
		(pad "2" smd custom
			(at 0 0.762)
			(size 0.2159 0.2159)
			(layers "F.Cu" "F.Mask" "F.Paste")
			(net "GND")
			(options
				(clearance outline)
				(anchor circle)
			)
			(primitives
				(gr_poly
					(pts
						(arc
							(start -0.3302 -0.4318)
							(mid -0.402042 -0.402042)
							(end -0.4318 -0.3302)
						)
						(arc
							(start -0.4318 0.3302)
							(mid -0.402042 0.402042)
							(end -0.3302 0.4318)
						)
						(arc
							(start 0.3302 0.4318)
							(mid 0.402042 0.402042)
							(end 0.4318 0.3302)
						)
						(arc
							(start 0.4318 -0.3302)
							(mid 0.402042 -0.402042)
							(end 0.3302 -0.4318)
						)
					)
					(width 0)
					(fill yes)
				)
			)
		)
	)
	(footprint ""
		(layer "F.Cu")
		(at 30.606746 -436.2577 90)
		(property "Reference" "U31"
			(at 0 0 90)
			(layer "F.SilkS")
			(hide yes)
			(effects
				(font
					(size 1.27 1.27)
				)
			)
		)
		(property "Value" "74LVC1G08GW-1-GP"
			(at -2.3368 -8.6868 90)
			(unlocked yes)
			(layer "F.Fab")
			(hide yes)
			(effects
				(font
					(size 1.016 1.016)
					(thickness 0.1524)
				)
			)
		)
		(property "Device Type" "SC70-5H44"
			(at -2.3114 -10.414 90)
			(unlocked yes)
			(layer "F.Fab")
			(hide yes)
			(effects
				(font
					(size 1.016 1.016)
					(thickness 0.1524)
				)
			)
		)
		(duplicate_pad_numbers_are_jumpers no)
		(fp_line
			(start 1.3843 -1.8034)
			(end 1.3843 -1.1176)
			(stroke
				(width 0.3302)
				(type default)
			)
			(layer "F.SilkS")
		)
		(fp_line
			(start 0.6604 -1.8034)
			(end 1.3843 -1.8034)
			(stroke
				(width 0.3302)
				(type default)
			)
			(layer "F.SilkS")
		)
		(fp_line
			(start 1.27 -1.7018)
			(end 1.27 1.7018)
			(stroke
				(width 0.1524)
				(type default)
			)
			(layer "F.SilkS")
		)
		(fp_line
			(start -1.27 -1.7018)
			(end 1.27 -1.7018)
			(stroke
				(width 0.1524)
				(type default)
			)
			(layer "F.SilkS")
		)
		(fp_line
			(start 1.27 1.7018)
			(end -1.27 1.7018)
			(stroke
				(width 0.1524)
				(type default)
			)
			(layer "F.SilkS")
		)
		(fp_line
			(start -1.27 1.7018)
			(end -1.27 -1.7018)
			(stroke
				(width 0.1524)
				(type default)
			)
			(layer "F.SilkS")
		)
		(fp_rect
			(start -1.524 1.9558)
			(end 1.524 -1.9558)
			(stroke
				(width 0)
				(type default)
			)
			(fill no)
			(layer "F.CrtYd")
		)
		(fp_poly
			(pts
				(xy -1.524 -1.9558) (xy 1.524 -1.9558) (xy 1.524 1.9558) (xy -1.524 1.9558)
			)
			(stroke
				(width 0)
				(type default)
			)
			(fill no)
			(layer "F.Fab")
		)
		(pad "1" smd rect
			(at 0.65024 -0.8255 90)
			(size 0.4064 1.2192)
			(layers "F.Cu" "F.Mask" "F.Paste")
			(net "SAS2X28_B_HDD10_FLT")
		)
		(pad "2" smd rect
			(at 0 -0.8255 90)
			(size 0.4064 1.2192)
			(layers "F.Cu" "F.Mask" "F.Paste")
			(net "SAS2X28_A_HDD10_FLT")
		)
		(pad "3" smd rect
			(at -0.65024 -0.8255 90)
			(size 0.4064 1.2192)
			(layers "F.Cu" "F.Mask" "F.Paste")
			(net "GND")
		)
		(pad "4" smd rect
			(at -0.65024 0.8255 90)
			(size 0.4064 1.2192)
			(layers "F.Cu" "F.Mask" "F.Paste")
			(net "FLT_HDD10_DRIVE")
		)
		(pad "5" smd rect
			(at 0.65024 0.8255 90)
			(size 0.4064 1.2192)
			(layers "F.Cu" "F.Mask" "F.Paste")
			(net "P3V3")
		)
	)
)
